(kicad_pcb
	(version 20260206)
	(generator "pcbnew")
	(generator_version "10.0")
	(general
		(thickness 1.6)
		(legacy_teardrops no)
	)
	(paper "A4")
	(title_block
		(title "baseboard — 13948-1b.1110WZS1818.brd")
		(comment 1 "Honey Badger (Wiwynn) / footprints 2362-2368 of 2523")
	)
	(layers
		(0 "F.Cu" signal "TOP")
		(4 "In1.Cu" signal "L2GND")
		(6 "In2.Cu" signal "L3")
		(8 "In3.Cu" signal "L4VCC")
		(10 "In4.Cu" signal "L5VCC")
		(12 "In5.Cu" signal "L6")
		(14 "In6.Cu" signal "L7GND")
		(2 "B.Cu" signal "BOTTOM")
		(9 "F.Adhes" user "F.Adhesive")
		(11 "B.Adhes" user "B.Adhesive")
		(13 "F.Paste" user "Package Geometry/Pastemask Top")
		(15 "B.Paste" user "Package Geometry/Pastemask Bottom")
		(5 "F.SilkS" user "Ref Des/Silkscreen Top")
		(7 "B.SilkS" user "Ref Des/Silkscreen Bottom")
		(1 "F.Mask" user "Board Geometry/Soldermask Top")
		(3 "B.Mask" user "Board Geometry/Soldermask Bottom")
		(17 "Dwgs.User" user "User.Drawings")
		(19 "Cmts.User" user "User.Comments")
		(21 "Eco1.User" user "User.Eco1")
		(23 "Eco2.User" user "User.Eco2")
		(25 "Edge.Cuts" user "Board Geometry/Outline")
		(27 "Margin" user)
		(31 "F.CrtYd" user "Package Geometry/Place Bound Top")
		(29 "B.CrtYd" user "Package Geometry/Place Bound Bottom")
		(35 "F.Fab" user "Ref Des/Assembly Top")
		(33 "B.Fab" user "Ref Des/Assembly Bottom")
	)
	(footprint ""
		(layer "B.Cu")
		(at 108.020612 -205.867)
		(property "Reference" "SR897"
			(at 0 0 0)
			(layer "B.SilkS")
			(hide yes)
			(effects
				(font
					(size 1.27 1.27)
				)
				(justify mirror)
			)
		)
		(property "Value" "0R2J-2-GP"
			(at -0.064008 -3.993896 0)
			(unlocked yes)
			(layer "B.Fab")
			(hide yes)
			(effects
				(font
					(size 1.016 1.016)
					(thickness 0.1524)
				)
				(justify mirror)
			)
		)
		(property "Device Type" "R402H16"
			(at -0.064008 -5.517896 0)
			(unlocked yes)
			(layer "B.Fab")
			(hide yes)
			(effects
				(font
					(size 1.016 1.016)
					(thickness 0.1524)
				)
				(justify mirror)
			)
		)
		(duplicate_pad_numbers_are_jumpers no)
		(fp_line
			(start -0.508 -0.9398)
			(end 0.508 -0.9398)
			(stroke
				(width 0.1524)
				(type default)
			)
			(layer "B.SilkS")
		)
		(fp_line
			(start 0.508 -0.9398)
			(end 0.508 0.9398)
			(stroke
				(width 0.1524)
				(type default)
			)
			(layer "B.SilkS")
		)
		(fp_rect
			(start 0.508 0.9398)
			(end -0.508 -0.9398)
			(stroke
				(width 0)
				(type default)
			)
			(fill no)
			(layer "B.CrtYd")
		)
		(fp_rect
			(start 0.508 0.9398)
			(end -0.508 -0.9398)
			(stroke
				(width 0)
				(type default)
			)
			(fill no)
			(layer "B.Fab")
		)
		(pad "1" smd custom
			(at 0 -0.4445 180)
			(size 0.1397 0.1397)
			(layers "B.Cu" "B.Mask" "B.Paste")
			(net "SAS_HDD_REDV_SER_RX8_N")
			(options
				(clearance outline)
				(anchor circle)
			)
			(primitives
				(gr_poly
					(pts
						(arc
							(start -0.1778 0.2794)
							(mid -0.249642 0.249642)
							(end -0.2794 0.1778)
						)
						(arc
							(start -0.2794 -0.1778)
							(mid -0.249642 -0.249642)
							(end -0.1778 -0.2794)
						)
						(arc
							(start 0.1778 -0.2794)
							(mid 0.249642 -0.249642)
							(end 0.2794 -0.1778)
						)
						(arc
							(start 0.2794 0.1778)
							(mid 0.249642 0.249642)
							(end 0.1778 0.2794)
						)
					)
					(width 0)
					(fill yes)
				)
			)
		)
		(pad "2" smd custom
			(at 0 0.4445 180)
			(size 0.1397 0.1397)
			(layers "B.Cu" "B.Mask" "B.Paste")
			(net "SAS_HDD_CONN_RX8_N")
			(options
				(clearance outline)
				(anchor circle)
			)
			(primitives
				(gr_poly
					(pts
						(arc
							(start -0.1778 0.2794)
							(mid -0.249642 0.249642)
							(end -0.2794 0.1778)
						)
						(arc
							(start -0.2794 -0.1778)
							(mid -0.249642 -0.249642)
							(end -0.1778 -0.2794)
						)
						(arc
							(start 0.1778 -0.2794)
							(mid 0.249642 -0.249642)
							(end 0.2794 -0.1778)
						)
						(arc
							(start 0.2794 0.1778)
							(mid 0.249642 0.249642)
							(end 0.1778 0.2794)
						)
					)
					(width 0)
					(fill yes)
				)
			)
		)
	)
	(footprint ""
		(layer "B.Cu")
		(at 162.687 -89.154)
		(property "Reference" "PC176"
			(at 0 0 0)
			(layer "B.SilkS")
			(hide yes)
			(effects
				(font
					(size 1.27 1.27)
				)
				(justify mirror)
			)
		)
		(property "Value" "SC22U6D3V3MX-1-GP"
			(at 0 -2.8194 0)
			(unlocked yes)
			(layer "B.Fab")
			(hide yes)
			(effects
				(font
					(size 1.016 1.016)
					(thickness 0.1524)
				)
				(justify mirror)
			)
		)
		(property "Device Type" "C603H40"
			(at 0 -4.3434 0)
			(unlocked yes)
			(layer "B.Fab")
			(hide yes)
			(effects
				(font
					(size 1.016 1.016)
					(thickness 0.1524)
				)
				(justify mirror)
			)
		)
		(duplicate_pad_numbers_are_jumpers no)
		(fp_line
			(start -0.508 0)
			(end 0.508 0)
			(stroke
				(width 0.2032)
				(type default)
			)
			(layer "B.SilkS")
		)
		(fp_rect
			(start 0.5842 1.3335)
			(end -0.5842 -1.3335)
			(stroke
				(width 0)
				(type default)
			)
			(fill no)
			(layer "B.CrtYd")
		)
		(fp_rect
			(start 0.5842 1.3335)
			(end -0.5842 -1.3335)
			(stroke
				(width 0)
				(type default)
			)
			(fill no)
			(layer "B.Fab")
		)
		(pad "1" smd custom
			(at 0 -0.762 180)
			(size 0.2159 0.2159)
			(layers "B.Cu" "B.Mask" "B.Paste")
			(net "P0V9_E")
			(options
				(clearance outline)
				(anchor circle)
			)
			(primitives
				(gr_poly
					(pts
						(arc
							(start -0.3302 0.4318)
							(mid -0.402042 0.402042)
							(end -0.4318 0.3302)
						)
						(arc
							(start -0.4318 -0.3302)
							(mid -0.402042 -0.402042)
							(end -0.3302 -0.4318)
						)
						(arc
							(start 0.3302 -0.4318)
							(mid 0.402042 -0.402042)
							(end 0.4318 -0.3302)
						)
						(arc
							(start 0.4318 0.3302)
							(mid 0.402042 0.402042)
							(end 0.3302 0.4318)
						)
					)
					(width 0)
					(fill yes)
				)
			)
		)
		(pad "2" smd custom
			(at 0 0.762 180)
			(size 0.2159 0.2159)
			(layers "B.Cu" "B.Mask" "B.Paste")
			(net "GND")
			(options
				(clearance outline)
				(anchor circle)
			)
			(primitives
				(gr_poly
					(pts
						(arc
							(start -0.3302 0.4318)
							(mid -0.402042 0.402042)
							(end -0.4318 0.3302)
						)
						(arc
							(start -0.4318 -0.3302)
							(mid -0.402042 -0.402042)
							(end -0.3302 -0.4318)
						)
						(arc
							(start 0.3302 -0.4318)
							(mid 0.402042 -0.402042)
							(end 0.4318 -0.3302)
						)
						(arc
							(start 0.4318 0.3302)
							(mid 0.402042 0.402042)
							(end 0.3302 0.4318)
						)
					)
					(width 0)
					(fill yes)
				)
			)
		)
	)
	(footprint ""
		(layer "B.Cu")
		(at 26.366216 -232.33888)
		(property "Reference" "R503"
			(at 0 0 0)
			(layer "B.SilkS")
			(hide yes)
			(effects
				(font
					(size 1.27 1.27)
				)
				(justify mirror)
			)
		)
		(property "Value" "0R2J-2-GP"
			(at -0.064008 -3.993896 0)
			(unlocked yes)
			(layer "B.Fab")
			(hide yes)
			(effects
				(font
					(size 1.016 1.016)
					(thickness 0.1524)
				)
				(justify mirror)
			)
		)
		(property "Device Type" "R402H16"
			(at -0.064008 -5.517896 0)
			(unlocked yes)
			(layer "B.Fab")
			(hide yes)
			(effects
				(font
					(size 1.016 1.016)
					(thickness 0.1524)
				)
				(justify mirror)
			)
		)
		(duplicate_pad_numbers_are_jumpers no)
		(fp_line
			(start -0.508 -0.9398)
			(end 0.508 -0.9398)
			(stroke
				(width 0.1524)
				(type default)
			)
			(layer "B.SilkS")
		)
		(fp_line
			(start 0.508 -0.9398)
			(end 0.508 0.9398)
			(stroke
				(width 0.1524)
				(type default)
			)
			(layer "B.SilkS")
		)
		(fp_rect
			(start 0.508 0.9398)
			(end -0.508 -0.9398)
			(stroke
				(width 0)
				(type default)
			)
			(fill no)
			(layer "B.CrtYd")
		)
		(fp_rect
			(start 0.508 0.9398)
			(end -0.508 -0.9398)
			(stroke
				(width 0)
				(type default)
			)
			(fill no)
			(layer "B.Fab")
		)
		(pad "1" smd custom
			(at 0 -0.4445 180)
			(size 0.1397 0.1397)
			(layers "B.Cu" "B.Mask" "B.Paste")
			(net "SAS_HDD_PWR1_PCIE")
			(options
				(clearance outline)
				(anchor circle)
			)
			(primitives
				(gr_poly
					(pts
						(arc
							(start -0.1778 0.2794)
							(mid -0.249642 0.249642)
							(end -0.2794 0.1778)
						)
						(arc
							(start -0.2794 -0.1778)
							(mid -0.249642 -0.249642)
							(end -0.1778 -0.2794)
						)
						(arc
							(start 0.1778 -0.2794)
							(mid 0.249642 -0.249642)
							(end 0.2794 -0.1778)
						)
						(arc
							(start 0.2794 0.1778)
							(mid 0.249642 0.249642)
							(end 0.1778 0.2794)
						)
					)
					(width 0)
					(fill yes)
				)
			)
		)
		(pad "2" smd custom
			(at 0 0.4445 180)
			(size 0.1397 0.1397)
			(layers "B.Cu" "B.Mask" "B.Paste")
			(net "SAS_HDD_PWR1")
			(options
				(clearance outline)
				(anchor circle)
			)
			(primitives
				(gr_poly
					(pts
						(arc
							(start -0.1778 0.2794)
							(mid -0.249642 0.249642)
							(end -0.2794 0.1778)
						)
						(arc
							(start -0.2794 -0.1778)
							(mid -0.249642 -0.249642)
							(end -0.1778 -0.2794)
						)
						(arc
							(start 0.1778 -0.2794)
							(mid 0.249642 -0.249642)
							(end 0.2794 -0.1778)
						)
						(arc
							(start 0.2794 0.1778)
							(mid 0.249642 0.249642)
							(end 0.1778 0.2794)
						)
					)
					(width 0)
					(fill yes)
				)
			)
		)
	)
	(footprint ""
		(layer "B.Cu")
		(at 121.544842 -83.307682 90)
		(property "Reference" "SC1153"
			(at 0 0 90)
			(layer "B.SilkS")
			(hide yes)
			(effects
				(font
					(size 1.27 1.27)
				)
				(justify mirror)
			)
		)
		(property "Value" "SCD1U6D3V1KX-GP"
			(at 2.8321 -1.7399 90)
			(unlocked yes)
			(layer "B.Fab")
			(hide yes)
			(effects
				(font
					(size 1.016 1.016)
					(thickness 0.1524)
				)
				(justify mirror)
			)
		)
		(property "Device Type" "C0201H13"
			(at 2.8321 -3.2639 90)
			(unlocked yes)
			(layer "B.Fab")
			(hide yes)
			(effects
				(font
					(size 1.016 1.016)
					(thickness 0.1524)
				)
				(justify mirror)
			)
		)
		(duplicate_pad_numbers_are_jumpers no)
		(fp_rect
			(start 0.2794 0.6477)
			(end -0.2794 -0.6477)
			(stroke
				(width 0)
				(type default)
			)
			(fill no)
			(layer "B.CrtYd")
		)
		(fp_rect
			(start 0.2794 0.6477)
			(end -0.2794 -0.6477)
			(stroke
				(width 0)
				(type default)
			)
			(fill no)
			(layer "B.Fab")
		)
		(pad "1" smd custom
			(at 0 -0.2794 270)
			(size 0.0762 0.0762)
			(layers "B.Cu" "B.Mask" "B.Paste")
			(net "XTAL_VDDA18")
			(options
				(clearance outline)
				(anchor circle)
			)
			(primitives
				(gr_poly
					(pts
						(arc
							(start 0.1524 0.127)
							(mid 0.137521 0.162921)
							(end 0.1016 0.1778)
						)
						(arc
							(start -0.1016 0.1778)
							(mid -0.137521 0.162921)
							(end -0.1524 0.127)
						)
						(arc
							(start -0.1524 -0.127)
							(mid -0.137521 -0.162921)
							(end -0.1016 -0.1778)
						)
						(arc
							(start 0.1016 -0.1778)
							(mid 0.137521 -0.162921)
							(end 0.1524 -0.127)
						)
					)
					(width 0)
					(fill yes)
				)
			)
		)
		(pad "2" smd custom
			(at 0 0.2794 270)
			(size 0.0762 0.0762)
			(layers "B.Cu" "B.Mask" "B.Paste")
			(net "GND")
			(options
				(clearance outline)
				(anchor circle)
			)
			(primitives
				(gr_poly
					(pts
						(arc
							(start 0.1524 0.127)
							(mid 0.137521 0.162921)
							(end 0.1016 0.1778)
						)
						(arc
							(start -0.1016 0.1778)
							(mid -0.137521 0.162921)
							(end -0.1524 0.127)
						)
						(arc
							(start -0.1524 -0.127)
							(mid -0.137521 -0.162921)
							(end -0.1016 -0.1778)
						)
						(arc
							(start 0.1016 -0.1778)
							(mid 0.137521 -0.162921)
							(end 0.1524 -0.127)
						)
					)
					(width 0)
					(fill yes)
				)
			)
		)
	)
	(footprint ""
		(layer "B.Cu")
		(at 86.11616 -49.022 90)
		(property "Reference" "SR626"
			(at 0 0 90)
			(layer "B.SilkS")
			(hide yes)
			(effects
				(font
					(size 1.27 1.27)
				)
				(justify mirror)
			)
		)
		(property "Value" "2K2R2F-GP"
			(at -0.064008 -3.993896 90)
			(unlocked yes)
			(layer "B.Fab")
			(hide yes)
			(effects
				(font
					(size 1.016 1.016)
					(thickness 0.1524)
				)
				(justify mirror)
			)
		)
		(property "Device Type" "R402H16"
			(at -0.064008 -5.517896 90)
			(unlocked yes)
			(layer "B.Fab")
			(hide yes)
			(effects
				(font
					(size 1.016 1.016)
					(thickness 0.1524)
				)
				(justify mirror)
			)
		)
		(duplicate_pad_numbers_are_jumpers no)
		(fp_line
			(start 0.508 -0.9398)
			(end 0.508 0.9398)
			(stroke
				(width 0.1524)
				(type default)
			)
			(layer "B.SilkS")
		)
		(fp_line
			(start -0.508 -0.9398)
			(end 0.508 -0.9398)
			(stroke
				(width 0.1524)
				(type default)
			)
			(layer "B.SilkS")
		)
		(fp_rect
			(start 0.508 0.9398)
			(end -0.508 -0.9398)
			(stroke
				(width 0)
				(type default)
			)
			(fill no)
			(layer "B.CrtYd")
		)
		(fp_rect
			(start 0.508 0.9398)
			(end -0.508 -0.9398)
			(stroke
				(width 0)
				(type default)
			)
			(fill no)
			(layer "B.Fab")
		)
		(pad "1" smd custom
			(at 0 -0.4445 270)
			(size 0.1397 0.1397)
			(layers "B.Cu" "B.Mask" "B.Paste")
			(net "P1V8_C")
			(options
				(clearance outline)
				(anchor circle)
			)
			(primitives
				(gr_poly
					(pts
						(arc
							(start -0.1778 0.2794)
							(mid -0.249642 0.249642)
							(end -0.2794 0.1778)
						)
						(arc
							(start -0.2794 -0.1778)
							(mid -0.249642 -0.249642)
							(end -0.1778 -0.2794)
						)
						(arc
							(start 0.1778 -0.2794)
							(mid 0.249642 -0.249642)
							(end 0.2794 -0.1778)
						)
						(arc
							(start 0.2794 0.1778)
							(mid 0.249642 0.249642)
							(end 0.1778 0.2794)
						)
					)
					(width 0)
					(fill yes)
				)
			)
		)
		(pad "2" smd custom
			(at 0 0.4445 270)
			(size 0.1397 0.1397)
			(layers "B.Cu" "B.Mask" "B.Paste")
			(net "SIO_CLK_0")
			(options
				(clearance outline)
				(anchor circle)
			)
			(primitives
				(gr_poly
					(pts
						(arc
							(start -0.1778 0.2794)
							(mid -0.249642 0.249642)
							(end -0.2794 0.1778)
						)
						(arc
							(start -0.2794 -0.1778)
							(mid -0.249642 -0.249642)
							(end -0.1778 -0.2794)
						)
						(arc
							(start 0.1778 -0.2794)
							(mid 0.249642 -0.249642)
							(end 0.2794 -0.1778)
						)
						(arc
							(start 0.2794 0.1778)
							(mid 0.249642 0.249642)
							(end 0.1778 0.2794)
						)
					)
					(width 0)
					(fill yes)
				)
			)
		)
	)
	(footprint ""
		(layer "B.Cu")
		(at 79.248 -73.914 180)
		(property "Reference" "SR851"
			(at 0 0 0)
			(layer "B.SilkS")
			(hide yes)
			(effects
				(font
					(size 1.27 1.27)
				)
				(justify mirror)
			)
		)
		(property "Value" "4K7R2F-GP"
			(at -0.064008 -3.993896 180)
			(unlocked yes)
			(layer "B.Fab")
			(hide yes)
			(effects
				(font
					(size 1.016 1.016)
					(thickness 0.1524)
				)
				(justify mirror)
			)
		)
		(property "Device Type" "R402H16"
			(at -0.064008 -5.517896 180)
			(unlocked yes)
			(layer "B.Fab")
			(hide yes)
			(effects
				(font
					(size 1.016 1.016)
					(thickness 0.1524)
				)
				(justify mirror)
			)
		)
		(duplicate_pad_numbers_are_jumpers no)
		(fp_line
			(start 0.508 -0.9398)
			(end 0.508 0.9398)
			(stroke
				(width 0.1524)
				(type default)
			)
			(layer "B.SilkS")
		)
		(fp_line
			(start -0.508 -0.9398)
			(end 0.508 -0.9398)
			(stroke
				(width 0.1524)
				(type default)
			)
			(layer "B.SilkS")
		)
		(fp_rect
			(start 0.508 0.9398)
			(end -0.508 -0.9398)
			(stroke
				(width 0)
				(type default)
			)
			(fill no)
			(layer "B.CrtYd")
		)
		(fp_rect
			(start 0.508 0.9398)
			(end -0.508 -0.9398)
			(stroke
				(width 0)
				(type default)
			)
			(fill no)
			(layer "B.Fab")
		)
		(pad "1" smd custom
			(at 0 -0.4445)
			(size 0.1397 0.1397)
			(layers "B.Cu" "B.Mask" "B.Paste")
			(net "P1V8_C")
			(options
				(clearance outline)
				(anchor circle)
			)
			(primitives
				(gr_poly
					(pts
						(arc
							(start -0.1778 0.2794)
							(mid -0.249642 0.249642)
							(end -0.2794 0.1778)
						)
						(arc
							(start -0.2794 -0.1778)
							(mid -0.249642 -0.249642)
							(end -0.1778 -0.2794)
						)
						(arc
							(start 0.1778 -0.2794)
							(mid 0.249642 -0.249642)
							(end 0.2794 -0.1778)
						)
						(arc
							(start 0.2794 0.1778)
							(mid 0.249642 0.249642)
							(end 0.1778 0.2794)
						)
					)
					(width 0)
					(fill yes)
				)
			)
		)
		(pad "2" smd custom
			(at 0 0.4445)
			(size 0.1397 0.1397)
			(layers "B.Cu" "B.Mask" "B.Paste")
			(net "P0V955_C_PG_R")
			(options
				(clearance outline)
				(anchor circle)
			)
			(primitives
				(gr_poly
					(pts
						(arc
							(start -0.1778 0.2794)
							(mid -0.249642 0.249642)
							(end -0.2794 0.1778)
						)
						(arc
							(start -0.2794 -0.1778)
							(mid -0.249642 -0.249642)
							(end -0.1778 -0.2794)
						)
						(arc
							(start 0.1778 -0.2794)
							(mid 0.249642 -0.249642)
							(end 0.2794 -0.1778)
						)
						(arc
							(start 0.2794 0.1778)
							(mid 0.249642 0.249642)
							(end 0.1778 0.2794)
						)
					)
					(width 0)
					(fill yes)
				)
			)
		)
	)
	(footprint ""
		(layer "B.Cu")
		(at 127.09017 -87.4776 90)
		(property "Reference" "SC1160"
			(at 0 0 90)
			(layer "B.SilkS")
			(hide yes)
			(effects
				(font
					(size 1.27 1.27)
				)
				(justify mirror)
			)
		)
		(property "Value" "SC1U6D3V1MX-GP"
			(at -1.9177 2.0193 90)
			(unlocked yes)
			(layer "B.Fab")
			(hide yes)
			(effects
				(font
					(size 1.016 1.016)
					(thickness 0.1524)
				)
				(justify mirror)
			)
		)
		(property "Device Type" "C0201H14"
			(at -1.9177 0.4953 90)
			(unlocked yes)
			(layer "B.Fab")
			(hide yes)
			(effects
				(font
					(size 1.016 1.016)
					(thickness 0.1524)
				)
				(justify mirror)
			)
		)
		(duplicate_pad_numbers_are_jumpers no)
		(fp_rect
			(start 0.1524 0.3048)
			(end -0.1524 -0.3048)
			(stroke
				(width 0)
				(type default)
			)
			(fill no)
			(layer "B.CrtYd")
		)
		(fp_poly
			(pts
				(xy 0.2794 0.6477) (xy 0.2794 -0.6477) (xy -0.2794 -0.6477) (xy -0.2794 -0.1905) (xy -0.1524 -0.1905)
				(xy -0.1524 -0.3048) (xy 0.1524 -0.3048) (xy 0.1524 0.3048) (xy -0.1524 0.3048) (xy -0.1524 -0.1778)
				(xy -0.2794 -0.1778) (xy -0.2794 0.6477)
			)
			(stroke
				(width 0)
				(type default)
			)
			(fill no)
			(layer "B.CrtYd")
		)
		(fp_rect
			(start 0.2794 0.6477)
			(end -0.2794 -0.6477)
			(stroke
				(width 0)
				(type default)
			)
			(fill no)
			(layer "B.Fab")
		)
		(pad "1" smd custom
			(at 0 -0.2794 270)
			(size 0.0762 0.0762)
			(layers "B.Cu" "B.Mask" "B.Paste")
			(net "GB_VDDA")
			(options
				(clearance outline)
				(anchor circle)
			)
			(primitives
				(gr_poly
					(pts
						(arc
							(start 0.1524 0.127)
							(mid 0.137521 0.162921)
							(end 0.1016 0.1778)
						)
						(arc
							(start -0.1016 0.1778)
							(mid -0.137521 0.162921)
							(end -0.1524 0.127)
						)
						(arc
							(start -0.1524 -0.127)
							(mid -0.137521 -0.162921)
							(end -0.1016 -0.1778)
						)
						(arc
							(start 0.1016 -0.1778)
							(mid 0.137521 -0.162921)
							(end 0.1524 -0.127)
						)
					)
					(width 0)
					(fill yes)
				)
			)
		)
		(pad "2" smd custom
			(at 0 0.2794 270)
			(size 0.0762 0.0762)
			(layers "B.Cu" "B.Mask" "B.Paste")
			(net "GND")
			(options
				(clearance outline)
				(anchor circle)
			)
			(primitives
				(gr_poly
					(pts
						(arc
							(start 0.1524 0.127)
							(mid 0.137521 0.162921)
							(end 0.1016 0.1778)
						)
						(arc
							(start -0.1016 0.1778)
							(mid -0.137521 0.162921)
							(end -0.1524 0.127)
						)
						(arc
							(start -0.1524 -0.127)
							(mid -0.137521 -0.162921)
							(end -0.1016 -0.1778)
						)
						(arc
							(start 0.1016 -0.1778)
							(mid 0.137521 -0.162921)
							(end 0.1524 -0.127)
						)
					)
					(width 0)
					(fill yes)
				)
			)
		)
	)
)
